# SCM (Grand Teton) — schematic netlist excerpt (pin names and nets, part order shuffled) for the footprints in the layout excerpt that follows; sources: Cadence DE-HDL packaged netlist, KiCad conversion of 12092022_DA0F0TMDCD0_F0T_Management_Board_D_brd_V3_OCP.brd

R644  Q_RES  33.2 1% CHIP  pkg 0402LF  page 15 : A = FM_JTAG_BMC_MUX_SEL ; B = FM_JTAG_BMC_MUX_SEL_R1
C245  Q_CAP  0.1UF 25V 10% X7R  pkg 0402  page 41 : A = VCCIO2 ; B = GND

(kicad_pcb
	(version 20260206)
	(generator "pcbnew")
	(generator_version "10.0")
	(general
		(thickness 1.6)
		(legacy_teardrops no)
	)
	(paper "A4")
	(title_block
		(title "12092022_DA0F0TMDCD0_F0T_Management_Board_D_brd_V3_OCP.brd")
		(comment 1 "Grand Teton / footprints 843-844 of 1440")
	)
	(layers
		(0 "F.Cu" signal "TOP")
		(4 "In1.Cu" signal "GND")
		(6 "In2.Cu" signal "IN1")
		(8 "In3.Cu" signal "GND1")
		(10 "In4.Cu" signal "IN2")
		(12 "In5.Cu" signal "VCC")
		(14 "In6.Cu" signal "VCC1")
		(16 "In7.Cu" signal "IN3")
		(18 "In8.Cu" signal "GND2")
		(20 "In9.Cu" signal "IN4")
		(22 "In10.Cu" signal "GND3")
		(2 "B.Cu" signal "BOTTOM")
		(9 "F.Adhes" user "F.Adhesive")
		(11 "B.Adhes" user "B.Adhesive")
		(13 "F.Paste" user "Package Geometry/Pastemask Top")
		(15 "B.Paste" user "Package Geometry/Pastemask Bottom")
		(5 "F.SilkS" user "Ref Des/Silkscreen Top")
		(7 "B.SilkS" user "Ref Des/Silkscreen Bottom")
		(1 "F.Mask" user "Board Geometry/Soldermask Top")
		(3 "B.Mask" user "Board Geometry/Soldermask Bottom")
		(17 "Dwgs.User" user "User.Drawings")
		(19 "Cmts.User" user "User.Comments")
		(21 "Eco1.User" user "User.Eco1")
		(23 "Eco2.User" user "User.Eco2")
		(25 "Edge.Cuts" user "Board Geometry/Outline")
		(27 "Margin" user)
		(31 "F.CrtYd" user "Package Geometry/Place Bound Top")
		(29 "B.CrtYd" user "Package Geometry/Place Bound Bottom")
		(35 "F.Fab" user "Ref Des/Assembly Top")
		(33 "B.Fab" user "Ref Des/Assembly Bottom")
	)
	(footprint ""
		(layer "B.Cu")
		(at 38.608 -64.5922 90)
		(property "Reference" "R644"
			(at 0 0 90)
			(layer "B.SilkS")
			(hide yes)
			(effects
				(font
					(size 1.27 1.27)
				)
				(justify mirror)
			)
		)
		(property "Value" ""
			(at 0 0 90)
			(layer "B.Fab")
			(effects
				(font
					(size 1.27 1.27)
				)
				(justify mirror)
			)
		)
		(duplicate_pad_numbers_are_jumpers no)
		(fp_line
			(start 0.7874 -0.4064)
			(end -0.7874 -0.4064)
			(stroke
				(width 0.1524)
				(type default)
			)
			(layer "B.SilkS")
		)
		(fp_line
			(start -0.7874 -0.4064)
			(end -0.7874 0.4064)
			(stroke
				(width 0.1524)
				(type default)
			)
			(layer "B.SilkS")
		)
		(fp_line
			(start 0.7874 0.4064)
			(end 0.7874 -0.4064)
			(stroke
				(width 0.1524)
				(type default)
			)
			(layer "B.SilkS")
		)
		(fp_line
			(start -0.7874 0.4064)
			(end 0.7874 0.4064)
			(stroke
				(width 0.1524)
				(type default)
			)
			(layer "B.SilkS")
		)
		(fp_line
			(start 0.67945 -0.305054)
			(end 0.12065 -0.305054)
			(stroke
				(width 0.1)
				(type default)
			)
			(layer "B.Fab")
		)
		(fp_line
			(start 0.12065 -0.305054)
			(end 0.12065 -0.2794)
			(stroke
				(width 0.1)
				(type default)
			)
			(layer "B.Fab")
		)
		(fp_line
			(start -0.12065 -0.3048)
			(end -0.67945 -0.3048)
			(stroke
				(width 0.1)
				(type default)
			)
			(layer "B.Fab")
		)
		(fp_line
			(start -0.67945 -0.3048)
			(end -0.67945 0.3048)
			(stroke
				(width 0.1)
				(type default)
			)
			(layer "B.Fab")
		)
		(fp_line
			(start 0.12065 -0.2794)
			(end -0.12065 -0.2794)
			(stroke
				(width 0.1)
				(type default)
			)
			(layer "B.Fab")
		)
		(fp_line
			(start -0.12065 -0.2794)
			(end -0.12065 -0.3048)
			(stroke
				(width 0.1)
				(type default)
			)
			(layer "B.Fab")
		)
		(fp_line
			(start 0.12065 0.2794)
			(end 0.12065 0.3048)
			(stroke
				(width 0.1)
				(type default)
			)
			(layer "B.Fab")
		)
		(fp_line
			(start -0.120396 0.2794)
			(end 0.12065 0.2794)
			(stroke
				(width 0.1)
				(type default)
			)
			(layer "B.Fab")
		)
		(fp_line
			(start 0.67945 0.3048)
			(end 0.67945 -0.305054)
			(stroke
				(width 0.1)
				(type default)
			)
			(layer "B.Fab")
		)
		(fp_line
			(start 0.12065 0.3048)
			(end 0.67945 0.3048)
			(stroke
				(width 0.1)
				(type default)
			)
			(layer "B.Fab")
		)
		(fp_line
			(start -0.120396 0.3048)
			(end -0.120396 0.2794)
			(stroke
				(width 0.1)
				(type default)
			)
			(layer "B.Fab")
		)
		(fp_line
			(start -0.67945 0.3048)
			(end -0.120396 0.3048)
			(stroke
				(width 0.1)
				(type default)
			)
			(layer "B.Fab")
		)
		(pad "1" smd circle
			(at 0.40005 0 270)
			(size 0 0)
			(layers "B.Cu" "B.Mask" "B.Paste")
			(net "FM_JTAG_BMC_MUX_SEL")
		)
		(pad "2" smd circle
			(at -0.40005 0 270)
			(size 0 0)
			(layers "B.Cu" "B.Mask" "B.Paste")
			(net "FM_JTAG_BMC_MUX_SEL_R1")
		)
	)
	(footprint ""
		(layer "B.Cu")
		(at 21.059394 -95.187008 90)
		(property "Reference" "C245"
			(at 0 0 90)
			(layer "B.SilkS")
			(hide yes)
			(effects
				(font
					(size 1.27 1.27)
				)
				(justify mirror)
			)
		)
		(property "Value" ""
			(at 0 0 90)
			(layer "B.Fab")
			(effects
				(font
					(size 1.27 1.27)
				)
				(justify mirror)
			)
		)
		(duplicate_pad_numbers_are_jumpers no)
		(fp_line
			(start 0.69215 -0.2921)
			(end -0.69215 -0.2921)
			(stroke
				(width 0.1524)
				(type default)
			)
			(layer "B.SilkS")
		)
		(fp_line
			(start -0.69215 -0.2921)
			(end -0.69215 0.2921)
			(stroke
				(width 0.1524)
				(type default)
			)
			(layer "B.SilkS")
		)
		(fp_line
			(start 0.69215 0.2921)
			(end 0.69215 -0.2921)
			(stroke
				(width 0.1524)
				(type default)
			)
			(layer "B.SilkS")
		)
		(fp_line
			(start -0.69215 0.2921)
			(end 0.69215 0.2921)
			(stroke
				(width 0.1524)
				(type default)
			)
			(layer "B.SilkS")
		)
		(fp_line
			(start 0.51435 -0.2794)
			(end -0.51435 -0.2794)
			(stroke
				(width 0.1)
				(type default)
			)
			(layer "B.Fab")
		)
		(fp_line
			(start -0.51435 -0.2794)
			(end -0.51435 0.2794)
			(stroke
				(width 0.1)
				(type default)
			)
			(layer "B.Fab")
		)
		(fp_line
			(start 0.51435 0.2794)
			(end 0.51435 -0.2794)
			(stroke
				(width 0.1)
				(type default)
			)
			(layer "B.Fab")
		)
		(fp_line
			(start -0.51435 0.2794)
			(end 0.51435 0.2794)
			(stroke
				(width 0.1)
				(type default)
			)
			(layer "B.Fab")
		)
		(pad "1" smd circle
			(at 0.40005 0 270)
			(size 0 0)
			(layers "B.Cu" "B.Mask" "B.Paste")
			(net "VCCIO2")
		)
		(pad "2" smd circle
			(at -0.40005 0 270)
			(size 0 0)
			(layers "B.Cu" "B.Mask" "B.Paste")
			(net "GND")
		)
		(zone
			(layer "B.Cu")
			(hatch none 0.5)
			(connect_pads
				(clearance 0)
			)
			(min_thickness 0.25)
			(keepout
				(tracks not_allowed)
				(vias allowed)
				(pads allowed)
				(copperpour not_allowed)
				(footprints allowed)
			)
			(placement
				(enabled no)
				(sheetname "")
			)
			(fill
				(thermal_gap 0.5)
				(thermal_bridge_width 0.5)
				(island_removal_mode 0)
			)
			(polygon
				(pts
					(xy 21.147024 -95.377508) (xy 21.20519 -95.286068) (xy 21.20519 -95.086678) (xy 21.147024 -94.996508)
					(xy 20.971764 -94.996508) (xy 20.913344 -95.086678) (xy 20.913344 -95.286068) (xy 20.97151 -95.377508)
				)
			)
		)
	)
)
